# S9S_MB_2U (Grand Teton) — schematic netlist excerpt (pin names and nets, part order shuffled) for the footprints in the layout excerpt that follows; sources: Cadence DE-HDL packaged netlist, KiCad conversion of 03242023_DA0F0TMBIJ0_F0T_Motherboard_J_brd_V01_OCP.brd

C2352  Q_CAP  0.1UF 25V 10% EMPTY  pkg 0402  page 167 : A = P2E_MB_BMC_TX_BUF2_DN<0> ; B = P2E_MB_BMC_TX_BUF_C_DN<0>
R3582  Q_RES  2.2K 5% CHIP  pkg 0402LF  page 231 : A = P3V3_AUX ; B = SMB_IOEXP_3V3AUX_SCL

(kicad_pcb
	(version 20260206)
	(generator "pcbnew")
	(generator_version "10.0")
	(general
		(thickness 1.6)
		(legacy_teardrops no)
	)
	(paper "A4")
	(title_block
		(title "03242023_DA0F0TMBIJ0_F0T_Motherboard_J_brd_V01_OCP.brd")
		(comment 1 "Grand Teton / footprints 3073-3074 of 6105")
	)
	(layers
		(0 "F.Cu" signal "TOP")
		(4 "In1.Cu" signal "GND")
		(6 "In2.Cu" signal "IN1")
		(8 "In3.Cu" signal "GND1")
		(10 "In4.Cu" signal "IN2")
		(12 "In5.Cu" signal "GND2")
		(14 "In6.Cu" signal "IN3")
		(16 "In7.Cu" signal "GND3")
		(18 "In8.Cu" signal "VCC")
		(20 "In9.Cu" signal "VCC1")
		(22 "In10.Cu" signal "GND4")
		(24 "In11.Cu" signal "IN4")
		(26 "In12.Cu" signal "GND5")
		(28 "In13.Cu" signal "IN5")
		(30 "In14.Cu" signal "GND6")
		(32 "In15.Cu" signal "IN6")
		(34 "In16.Cu" signal "GND7")
		(2 "B.Cu" signal "BOTTOM")
		(9 "F.Adhes" user "F.Adhesive")
		(11 "B.Adhes" user "B.Adhesive")
		(13 "F.Paste" user "Package Geometry/Pastemask Top")
		(15 "B.Paste" user "Package Geometry/Pastemask Bottom")
		(5 "F.SilkS" user "Ref Des/Silkscreen Top")
		(7 "B.SilkS" user "Ref Des/Silkscreen Bottom")
		(1 "F.Mask" user "Board Geometry/Soldermask Top")
		(3 "B.Mask" user "Board Geometry/Soldermask Bottom")
		(17 "Dwgs.User" user "User.Drawings")
		(19 "Cmts.User" user "User.Comments")
		(21 "Eco1.User" user "User.Eco1")
		(23 "Eco2.User" user "User.Eco2")
		(25 "Edge.Cuts" user "Board Geometry/Outline")
		(27 "Margin" user)
		(31 "F.CrtYd" user "Package Geometry/Place Bound Top")
		(29 "B.CrtYd" user "Package Geometry/Place Bound Bottom")
		(35 "F.Fab" user "Ref Des/Assembly Top")
		(33 "B.Fab" user "Ref Des/Assembly Bottom")
	)
	(footprint ""
		(layer "F.Cu")
		(at 19.927824 -396.812008 -90)
		(property "Reference" "C2352"
			(at 0 0 270)
			(layer "F.SilkS")
			(hide yes)
			(effects
				(font
					(size 1.27 1.27)
				)
			)
		)
		(property "Value" ""
			(at 0 0 270)
			(layer "F.Fab")
			(effects
				(font
					(size 1.27 1.27)
				)
			)
		)
		(duplicate_pad_numbers_are_jumpers no)
		(fp_line
			(start 0.020828 0.4064)
			(end -0.7874 0.4064)
			(stroke
				(width 0.1524)
				(type default)
			)
			(layer "F.SilkS")
		)
		(fp_line
			(start -0.7874 -0.4064)
			(end 0.7874 -0.4064)
			(stroke
				(width 0.1524)
				(type default)
			)
			(layer "F.SilkS")
		)
		(fp_line
			(start 0.7874 -0.4064)
			(end 0.7874 0.4064)
			(stroke
				(width 0.1524)
				(type default)
			)
			(layer "F.SilkS")
		)
		(fp_line
			(start -0.6858 0.3048)
			(end -0.6858 -0.3048)
			(stroke
				(width 0.1)
				(type default)
			)
			(layer "F.Fab")
		)
		(fp_line
			(start -0.1016 0.3048)
			(end -0.6858 0.3048)
			(stroke
				(width 0.1)
				(type default)
			)
			(layer "F.Fab")
		)
		(fp_line
			(start 0.1016 0.3048)
			(end 0.1016 0.2794)
			(stroke
				(width 0.1)
				(type default)
			)
			(layer "F.Fab")
		)
		(fp_line
			(start 0.6858 0.3048)
			(end 0.1016 0.3048)
			(stroke
				(width 0.1)
				(type default)
			)
			(layer "F.Fab")
		)
		(fp_line
			(start -0.1016 0.2794)
			(end -0.1016 0.3048)
			(stroke
				(width 0.1)
				(type default)
			)
			(layer "F.Fab")
		)
		(fp_line
			(start 0.1016 0.2794)
			(end -0.1016 0.2794)
			(stroke
				(width 0.1)
				(type default)
			)
			(layer "F.Fab")
		)
		(fp_line
			(start -0.1016 -0.2794)
			(end 0.1016 -0.2794)
			(stroke
				(width 0.1)
				(type default)
			)
			(layer "F.Fab")
		)
		(fp_line
			(start 0.1016 -0.2794)
			(end 0.1016 -0.3048)
			(stroke
				(width 0.1)
				(type default)
			)
			(layer "F.Fab")
		)
		(fp_line
			(start -0.6858 -0.3048)
			(end -0.1016 -0.3048)
			(stroke
				(width 0.1)
				(type default)
			)
			(layer "F.Fab")
		)
		(fp_line
			(start -0.1016 -0.3048)
			(end -0.1016 -0.2794)
			(stroke
				(width 0.1)
				(type default)
			)
			(layer "F.Fab")
		)
		(fp_line
			(start 0.1016 -0.3048)
			(end 0.6858 -0.3048)
			(stroke
				(width 0.1)
				(type default)
			)
			(layer "F.Fab")
		)
		(fp_line
			(start 0.6858 -0.3048)
			(end 0.6858 0.3048)
			(stroke
				(width 0.1)
				(type default)
			)
			(layer "F.Fab")
		)
		(pad "1" smd rect
			(at -0.40005 0 90)
			(size 0.4572 0.508)
			(layers "F.Cu" "F.Mask" "F.Paste")
			(net "P2E_MB_BMC_TX_BUF2_DN<0>")
		)
		(pad "2" smd rect
			(at 0.40005 0 90)
			(size 0.4572 0.508)
			(layers "F.Cu" "F.Mask" "F.Paste")
			(net "P2E_MB_BMC_TX_BUF_C_DN<0>")
		)
	)
	(footprint ""
		(layer "F.Cu")
		(at 111.332772 -132.266182)
		(property "Reference" "R3582"
			(at 0 0 0)
			(layer "F.SilkS")
			(hide yes)
			(effects
				(font
					(size 1.27 1.27)
				)
			)
		)
		(property "Value" ""
			(at 0 0 0)
			(layer "F.Fab")
			(effects
				(font
					(size 1.27 1.27)
				)
			)
		)
		(duplicate_pad_numbers_are_jumpers no)
		(fp_line
			(start -0.7874 -0.4064)
			(end 0.7874 -0.4064)
			(stroke
				(width 0.1524)
				(type default)
			)
			(layer "F.SilkS")
		)
		(fp_line
			(start -0.7874 0.4064)
			(end -0.7874 -0.4064)
			(stroke
				(width 0.1524)
				(type default)
			)
			(layer "F.SilkS")
		)
		(fp_line
			(start 0.7874 -0.4064)
			(end 0.7874 0.4064)
			(stroke
				(width 0.1524)
				(type default)
			)
			(layer "F.SilkS")
		)
		(fp_line
			(start 0.7874 0.4064)
			(end -0.7874 0.4064)
			(stroke
				(width 0.1524)
				(type default)
			)
			(layer "F.SilkS")
		)
		(fp_line
			(start -0.67945 -0.305054)
			(end -0.12065 -0.305054)
			(stroke
				(width 0.1)
				(type default)
			)
			(layer "F.Fab")
		)
		(fp_line
			(start -0.67945 0.3048)
			(end -0.67945 -0.305054)
			(stroke
				(width 0.1)
				(type default)
			)
			(layer "F.Fab")
		)
		(fp_line
			(start -0.12065 -0.305054)
			(end -0.12065 -0.2794)
			(stroke
				(width 0.1)
				(type default)
			)
			(layer "F.Fab")
		)
		(fp_line
			(start -0.12065 -0.2794)
			(end 0.12065 -0.2794)
			(stroke
				(width 0.1)
				(type default)
			)
			(layer "F.Fab")
		)
		(fp_line
			(start -0.12065 0.2794)
			(end -0.12065 0.3048)
			(stroke
				(width 0.1)
				(type default)
			)
			(layer "F.Fab")
		)
		(fp_line
			(start -0.12065 0.3048)
			(end -0.67945 0.3048)
			(stroke
				(width 0.1)
				(type default)
			)
			(layer "F.Fab")
		)
		(fp_line
			(start 0.120396 0.2794)
			(end -0.12065 0.2794)
			(stroke
				(width 0.1)
				(type default)
			)
			(layer "F.Fab")
		)
		(fp_line
			(start 0.120396 0.3048)
			(end 0.120396 0.2794)
			(stroke
				(width 0.1)
				(type default)
			)
			(layer "F.Fab")
		)
		(fp_line
			(start 0.12065 -0.3048)
			(end 0.67945 -0.3048)
			(stroke
				(width 0.1)
				(type default)
			)
			(layer "F.Fab")
		)
		(fp_line
			(start 0.12065 -0.2794)
			(end 0.12065 -0.3048)
			(stroke
				(width 0.1)
				(type default)
			)
			(layer "F.Fab")
		)
		(fp_line
			(start 0.67945 -0.3048)
			(end 0.67945 0.3048)
			(stroke
				(width 0.1)
				(type default)
			)
			(layer "F.Fab")
		)
		(fp_line
			(start 0.67945 0.3048)
			(end 0.120396 0.3048)
			(stroke
				(width 0.1)
				(type default)
			)
			(layer "F.Fab")
		)
		(pad "1" smd circle
			(at -0.40005 0)
			(size 0 0)
			(layers "F.Cu" "F.Mask" "F.Paste")
			(net "P3V3_AUX")
		)
		(pad "2" smd circle
			(at 0.40005 0)
			(size 0 0)
			(layers "F.Cu" "F.Mask" "F.Paste")
			(net "SMB_IOEXP_3V3AUX_SCL")
		)
	)
)
